(kicad_pcb
	(version 20241229)
	(generator "pcbnew")
	(generator_version "9.0")
	(general
		(thickness 1.6642)
		(legacy_teardrops no)
	)
	(paper "A3")
	(title_block
		(title "PolarFire SoM")
		(date "2025-07-22")
		(rev "1.1.4")
		(company "Antmicro Ltd")
		(comment 1 "www.antmicro.com")
		(comment 9 "footprints 209-212 of 470")
	)
	(layers
		(0 "F.Cu" mixed)
		(4 "In1.Cu" power)
		(6 "In2.Cu" signal)
		(8 "In3.Cu" power)
		(10 "In4.Cu" signal)
		(12 "In5.Cu" power)
		(14 "In6.Cu" power)
		(16 "In7.Cu" signal)
		(18 "In8.Cu" power)
		(20 "In9.Cu" signal)
		(22 "In10.Cu" power)
		(24 "In11.Cu" signal)
		(26 "In12.Cu" signal)
		(2 "B.Cu" mixed)
		(9 "F.Adhes" user "F.Adhesive")
		(11 "B.Adhes" user "B.Adhesive")
		(13 "F.Paste" user)
		(15 "B.Paste" user)
		(5 "F.SilkS" user "F.Silkscreen")
		(7 "B.SilkS" user "B.Silkscreen")
		(1 "F.Mask" user)
		(3 "B.Mask" user)
		(17 "Dwgs.User" user "User.Drawings")
		(19 "Cmts.User" user "User.Comments")
		(21 "Eco1.User" user "User.Eco1")
		(23 "Eco2.User" user "User.Eco2")
		(25 "Edge.Cuts" user)
		(27 "Margin" user)
		(31 "F.CrtYd" user "F.Courtyard")
		(29 "B.CrtYd" user "B.Courtyard")
		(35 "F.Fab" user)
		(33 "B.Fab" user)
	)
	(footprint "antmicro-footprints:C_0402_1005Metric"
		(layer "B.Cu")
		(at 194.73 133.1)
		(descr "Capacitor SMD 0402")
		(tags "capacitor SMD 0402")
		(property "Reference" "C49"
			(at -1.155 -0.25 180)
			(layer "B.SilkS")
			(effects
				(font
					(size 0.7 0.7)
					(thickness 0.15)
				)
				(justify left bottom mirror)
			)
		)
		(property "Value" "C_10u_0402"
			(at -1.022927 -2.155213 180)
			(layer "B.Fab")
			(hide yes)
			(effects
				(font
					(size 0.7 0.7)
					(thickness 0.15)
				)
				(justify left bottom mirror)
			)
		)
		(property "Datasheet" "https://www.yageo.com/en/Chart/Download/pdf/CC0402MRX5R5BB106"
			(at 0 0 0)
			(layer "F.Fab")
			(hide yes)
			(effects
				(font
					(size 1.27 1.27)
					(thickness 0.15)
				)
			)
		)
		(property "Description" "SMD Multilayer Ceramic Capacitor, 10 µF, 6.3 V, 0402 [1005 Metric], ± 20%, X5R, CC Series"
			(at 0 0 0)
			(layer "F.Fab")
			(hide yes)
			(effects
				(font
					(size 1.27 1.27)
					(thickness 0.15)
				)
			)
		)
		(property "Author" "Antmicro"
			(at 0 0 0)
			(layer "B.Fab")
			(hide yes)
			(effects
				(font
					(size 1 1)
					(thickness 0.15)
				)
				(justify mirror)
			)
		)
		(property "Dielectric" ""
			(at 0 0 0)
			(layer "B.Fab")
			(hide yes)
			(effects
				(font
					(size 1 1)
					(thickness 0.15)
				)
				(justify mirror)
			)
		)
		(property "License" "Apache-2.0"
			(at 0 0 0)
			(layer "B.Fab")
			(hide yes)
			(effects
				(font
					(size 1 1)
					(thickness 0.15)
				)
				(justify mirror)
			)
		)
		(property "MPN" "CC0402MRX5R5BB106"
			(at 0 0 0)
			(layer "B.Fab")
			(hide yes)
			(effects
				(font
					(size 1 1)
					(thickness 0.15)
				)
				(justify mirror)
			)
		)
		(property "Manufacturer" "YAGEO"
			(at 0 0 0)
			(layer "B.Fab")
			(hide yes)
			(effects
				(font
					(size 1 1)
					(thickness 0.15)
				)
				(justify mirror)
			)
		)
		(property "Public" ""
			(at 0 0 0)
			(layer "B.Fab")
			(hide yes)
			(effects
				(font
					(size 1 1)
					(thickness 0.15)
				)
				(justify mirror)
			)
		)
		(property "Val" "10u"
			(at 0 0 0)
			(layer "B.Fab")
			(hide yes)
			(effects
				(font
					(size 1 1)
					(thickness 0.15)
				)
				(justify mirror)
			)
		)
		(property "Voltage" ""
			(at 0 0 0)
			(layer "B.Fab")
			(hide yes)
			(effects
				(font
					(size 1 1)
					(thickness 0.15)
				)
				(justify mirror)
			)
		)
		(sheetname "/FPGA Supply/")
		(sheetfile "fpga-supply.kicad_sch")
		(attr smd)
		(fp_rect
			(start -0.925 0.47)
			(end 0.925 -0.47)
			(stroke
				(width 0.05)
				(type default)
			)
			(fill no)
			(layer "B.CrtYd")
		)
		(fp_line
			(start -0.494 -0.248)
			(end -0.494 0.25)
			(stroke
				(width 0.15)
				(type solid)
			)
			(layer "B.Fab")
		)
		(fp_line
			(start -0.494 0.25)
			(end 0.504 0.25)
			(stroke
				(width 0.15)
				(type solid)
			)
			(layer "B.Fab")
		)
		(fp_line
			(start 0.504 -0.248)
			(end -0.494 -0.248)
			(stroke
				(width 0.15)
				(type solid)
			)
			(layer "B.Fab")
		)
		(fp_line
			(start 0.504 0.25)
			(end 0.504 -0.248)
			(stroke
				(width 0.15)
				(type solid)
			)
			(layer "B.Fab")
		)
		(fp_text user "Author: Antmicro"
			(at -0.939 -3.399 180)
			(layer "B.Fab")
			(effects
				(font
					(size 0.7 0.7)
					(thickness 0.15)
				)
				(justify left bottom mirror)
			)
		)
		(fp_text user "License: Apache-2.0"
			(at -0.939 -5.799 180)
			(layer "B.Fab")
			(effects
				(font
					(size 0.7 0.7)
					(thickness 0.15)
				)
				(justify left bottom mirror)
			)
		)
		(fp_text user "${REFERENCE}"
			(at -0.939 -4.599 180)
			(layer "B.Fab")
			(effects
				(font
					(size 0.7 0.7)
					(thickness 0.15)
				)
				(justify left bottom mirror)
			)
		)
		(pad "1" smd roundrect
			(at -0.48 0)
			(size 0.59 0.64)
			(layers "B.Cu" "B.Mask" "B.Paste")
			(roundrect_rratio 0.25)
			(net 417 "GND")
			(pintype "passive")
		)
		(pad "2" smd roundrect
			(at 0.48 0)
			(size 0.59 0.64)
			(layers "B.Cu" "B.Mask" "B.Paste")
			(roundrect_rratio 0.25)
			(net 48 "+1V8")
			(pintype "passive")
		)
	)
	(footprint "antmicro-footprints:R_0402_1005Metric"
		(layer "B.Cu")
		(at 210.1925 129.35)
		(descr "Resistor SMD 0402")
		(tags "resistor SMD 0402")
		(property "Reference" "R37"
			(at -0.8425 0.628 180)
			(layer "B.SilkS")
			(effects
				(font
					(size 0.7 0.7)
					(thickness 0.15)
				)
				(justify left bottom mirror)
			)
		)
		(property "Value" "R_49k9_0402"
			(at -1.011843 -1.772047 180)
			(layer "B.Fab")
			(hide yes)
			(effects
				(font
					(size 0.7 0.7)
					(thickness 0.15)
				)
				(justify left bottom mirror)
			)
		)
		(property "Datasheet" "https://www.bourns.com/docs/product-datasheets/cr.pdf"
			(at 0 0 0)
			(layer "F.Fab")
			(hide yes)
			(effects
				(font
					(size 1.27 1.27)
					(thickness 0.15)
				)
			)
		)
		(property "Description" "SMD Chip Resistor, 49.9 kohm, ± 1%, 63 mW, 0402 [1005 Metric], Thick Film, General Purpose"
			(at 0 0 0)
			(layer "F.Fab")
			(hide yes)
			(effects
				(font
					(size 1.27 1.27)
					(thickness 0.15)
				)
			)
		)
		(property "Author" "Antmicro"
			(at 0 0 0)
			(layer "B.Fab")
			(hide yes)
			(effects
				(font
					(size 1 1)
					(thickness 0.15)
				)
				(justify mirror)
			)
		)
		(property "License" "Apache-2.0"
			(at 0 0 0)
			(layer "B.Fab")
			(hide yes)
			(effects
				(font
					(size 1 1)
					(thickness 0.15)
				)
				(justify mirror)
			)
		)
		(property "MPN" "CR0402-FX-4992GLF"
			(at 0 0 0)
			(layer "B.Fab")
			(hide yes)
			(effects
				(font
					(size 1 1)
					(thickness 0.15)
				)
				(justify mirror)
			)
		)
		(property "Manufacturer" "Bourns"
			(at 0 0 0)
			(layer "B.Fab")
			(hide yes)
			(effects
				(font
					(size 1 1)
					(thickness 0.15)
				)
				(justify mirror)
			)
		)
		(property "Public" ""
			(at 0 0 0)
			(layer "B.Fab")
			(hide yes)
			(effects
				(font
					(size 1 1)
					(thickness 0.15)
				)
				(justify mirror)
			)
		)
		(property "Tolerance" "1%"
			(at 0 0 0)
			(layer "B.Fab")
			(hide yes)
			(effects
				(font
					(size 1 1)
					(thickness 0.15)
				)
				(justify mirror)
			)
		)
		(property "Val" "49k9"
			(at 0 0 0)
			(layer "B.Fab")
			(hide yes)
			(effects
				(font
					(size 1 1)
					(thickness 0.15)
				)
				(justify mirror)
			)
		)
		(sheetname "/Memory/")
		(sheetfile "memory.kicad_sch")
		(attr smd)
		(fp_rect
			(start -0.925 0.47)
			(end 0.925 -0.47)
			(stroke
				(width 0.05)
				(type default)
			)
			(fill no)
			(layer "B.CrtYd")
		)
		(fp_rect
			(start -0.5 0.25)
			(end 0.5 -0.25)
			(stroke
				(width 0.15)
				(type solid)
			)
			(fill no)
			(layer "B.Fab")
		)
		(fp_text user "License: Apache-2.0"
			(at -0.95 -5.169 180)
			(layer "B.Fab")
			(effects
				(font
					(size 0.7 0.7)
					(thickness 0.15)
				)
				(justify left bottom mirror)
			)
		)
		(fp_text user "${REFERENCE}"
			(at -0.95 -3.168 180)
			(layer "B.Fab")
			(effects
				(font
					(size 0.7 0.7)
					(thickness 0.15)
				)
				(justify left bottom mirror)
			)
		)
		(fp_text user "Author: Antmicro"
			(at -0.95 -4.169 180)
			(layer "B.Fab")
			(effects
				(font
					(size 0.7 0.7)
					(thickness 0.15)
				)
				(justify left bottom mirror)
			)
		)
		(pad "1" smd roundrect
			(at -0.48 0)
			(size 0.59 0.64)
			(layers "B.Cu" "B.Mask" "B.Paste")
			(roundrect_rratio 0.25)
			(net 243 "/FPGA MSSIO/EMMC.DAT1")
			(pintype "passive")
		)
		(pad "2" smd roundrect
			(at 0.48 0)
			(size 0.59 0.64)
			(layers "B.Cu" "B.Mask" "B.Paste")
			(roundrect_rratio 0.25)
			(net 137 "SD_VDD")
			(pintype "passive")
		)
	)
	(footprint "antmicro-footprints:C_0402_1005Metric"
		(layer "B.Cu")
		(at 216.14 152.97 180)
		(descr "Capacitor SMD 0402")
		(tags "capacitor SMD 0402")
		(property "Reference" "C176"
			(at -3.74 -0.6 0)
			(layer "B.SilkS")
			(effects
				(font
					(size 0.7 0.7)
					(thickness 0.15)
				)
				(justify left bottom mirror)
			)
		)
		(property "Value" "C_100n_0402"
			(at -1.022927 -2.155213 0)
			(layer "B.Fab")
			(hide yes)
			(effects
				(font
					(size 0.7 0.7)
					(thickness 0.15)
				)
				(justify left bottom mirror)
			)
		)
		(property "Datasheet" "https://www.murata.com/products/productdetail?partno=GRM155R61H104KE14%23"
			(at 0 0 180)
			(layer "F.Fab")
			(hide yes)
			(effects
				(font
					(size 1.27 1.27)
					(thickness 0.15)
				)
			)
		)
		(property "Description" "SMD Multilayer Ceramic Capacitor, 0.1 µF, 50 V, 0402 [1005 Metric], ± 10%, X5R, GRM Series"
			(at 0 0 180)
			(layer "F.Fab")
			(hide yes)
			(effects
				(font
					(size 1.27 1.27)
					(thickness 0.15)
				)
			)
		)
		(property "Author" "Antmicro"
			(at 432.28 305.94 0)
			(layer "B.Fab")
			(hide yes)
			(effects
				(font
					(size 1 1)
					(thickness 0.15)
				)
				(justify mirror)
			)
		)
		(property "Dielectric" "X5R"
			(at 432.28 305.94 0)
			(layer "B.Fab")
			(hide yes)
			(effects
				(font
					(size 1 1)
					(thickness 0.15)
				)
				(justify mirror)
			)
		)
		(property "License" "Apache-2.0"
			(at 432.28 305.94 0)
			(layer "B.Fab")
			(hide yes)
			(effects
				(font
					(size 1 1)
					(thickness 0.15)
				)
				(justify mirror)
			)
		)
		(property "MPN" "GRM155R61H104KE14D"
			(at 432.28 305.94 0)
			(layer "B.Fab")
			(hide yes)
			(effects
				(font
					(size 1 1)
					(thickness 0.15)
				)
				(justify mirror)
			)
		)
		(property "Manufacturer" "Murata"
			(at 432.28 305.94 0)
			(layer "B.Fab")
			(hide yes)
			(effects
				(font
					(size 1 1)
					(thickness 0.15)
				)
				(justify mirror)
			)
		)
		(property "Public" ""
			(at 432.28 305.94 0)
			(layer "B.Fab")
			(hide yes)
			(effects
				(font
					(size 1 1)
					(thickness 0.15)
				)
				(justify mirror)
			)
		)
		(property "Val" "100n"
			(at 432.28 305.94 0)
			(layer "B.Fab")
			(hide yes)
			(effects
				(font
					(size 1 1)
					(thickness 0.15)
				)
				(justify mirror)
			)
		)
		(property "Voltage" "50V"
			(at 432.28 305.94 0)
			(layer "B.Fab")
			(hide yes)
			(effects
				(font
					(size 1 1)
					(thickness 0.15)
				)
				(justify mirror)
			)
		)
		(sheetname "/USB/")
		(sheetfile "usb.kicad_sch")
		(attr smd)
		(fp_rect
			(start -0.925 0.47)
			(end 0.925 -0.47)
			(stroke
				(width 0.05)
				(type default)
			)
			(fill no)
			(layer "B.CrtYd")
		)
		(fp_line
			(start 0.504 0.25)
			(end 0.504 -0.248)
			(stroke
				(width 0.15)
				(type solid)
			)
			(layer "B.Fab")
		)
		(fp_line
			(start 0.504 -0.248)
			(end -0.494 -0.248)
			(stroke
				(width 0.15)
				(type solid)
			)
			(layer "B.Fab")
		)
		(fp_line
			(start -0.494 0.25)
			(end 0.504 0.25)
			(stroke
				(width 0.15)
				(type solid)
			)
			(layer "B.Fab")
		)
		(fp_line
			(start -0.494 -0.248)
			(end -0.494 0.25)
			(stroke
				(width 0.15)
				(type solid)
			)
			(layer "B.Fab")
		)
		(fp_text user "License: Apache-2.0"
			(at -0.939 -5.799 0)
			(layer "B.Fab")
			(effects
				(font
					(size 0.7 0.7)
					(thickness 0.15)
				)
				(justify left bottom mirror)
			)
		)
		(fp_text user "Author: Antmicro"
			(at -0.939 -3.399 0)
			(layer "B.Fab")
			(effects
				(font
					(size 0.7 0.7)
					(thickness 0.15)
				)
				(justify left bottom mirror)
			)
		)
		(fp_text user "${REFERENCE}"
			(at -0.939 -4.599 0)
			(layer "B.Fab")
			(effects
				(font
					(size 0.7 0.7)
					(thickness 0.15)
				)
				(justify left bottom mirror)
			)
		)
		(pad "1" smd roundrect
			(at -0.48 0 180)
			(size 0.59 0.64)
			(layers "B.Cu" "B.Mask" "B.Paste")
			(roundrect_rratio 0.25)
			(net 417 "GND")
			(pintype "passive")
		)
		(pad "2" smd roundrect
			(at 0.48 0 180)
			(size 0.59 0.64)
			(layers "B.Cu" "B.Mask" "B.Paste")
			(roundrect_rratio 0.25)
			(net 50 "+3V3")
			(pintype "passive")
		)
	)
	(footprint "antmicro-footprints:C_0402_1005Metric"
		(layer "B.Cu")
		(at 184.4 130.25)
		(descr "Capacitor SMD 0402")
		(tags "capacitor SMD 0402")
		(property "Reference" "C155"
			(at -3.75 0.3 0)
			(layer "B.SilkS")
			(effects
				(font
					(size 0.7 0.7)
					(thickness 0.15)
				)
				(justify right bottom mirror)
			)
		)
		(property "Value" "C_1u_0402"
			(at -1.022927 -2.155213 0)
			(layer "B.Fab")
			(hide yes)
			(effects
				(font
					(size 0.7 0.7)
					(thickness 0.15)
				)
				(justify right bottom mirror)
			)
		)
		(property "Datasheet" "https://product.tdk.com/en/search/capacitor/ceramic/mlcc/info?part_no=C1005X6S1A105K050BC"
			(at 0 0 0)
			(layer "F.Fab")
			(hide yes)
			(effects
				(font
					(size 1.27 1.27)
					(thickness 0.15)
				)
			)
		)
		(property "Description" "SMD Multilayer Ceramic Capacitor, 1 µF, 10 V, 0402 [1005 Metric], ± 10%, X6S, C"
			(at 0 0 0)
			(layer "F.Fab")
			(hide yes)
			(effects
				(font
					(size 1.27 1.27)
					(thickness 0.15)
				)
			)
		)
		(property "Author" "Antmicro"
			(at 0 0 0)
			(layer "B.Fab")
			(hide yes)
			(effects
				(font
					(size 1 1)
					(thickness 0.15)
				)
				(justify mirror)
			)
		)
		(property "Dielectric" "X5R"
			(at 0 0 0)
			(layer "B.Fab")
			(hide yes)
			(effects
				(font
					(size 1 1)
					(thickness 0.15)
				)
				(justify mirror)
			)
		)
		(property "License" "Apache-2.0"
			(at 0 0 0)
			(layer "B.Fab")
			(hide yes)
			(effects
				(font
					(size 1 1)
					(thickness 0.15)
				)
				(justify mirror)
			)
		)
		(property "MPN" "C1005X6S1A105K050BC"
			(at 0 0 0)
			(layer "B.Fab")
			(hide yes)
			(effects
				(font
					(size 1 1)
					(thickness 0.15)
				)
				(justify mirror)
			)
		)
		(property "Manufacturer" "TDK"
			(at 0 0 0)
			(layer "B.Fab")
			(hide yes)
			(effects
				(font
					(size 1 1)
					(thickness 0.15)
				)
				(justify mirror)
			)
		)
		(property "Public" ""
			(at 0 0 0)
			(layer "B.Fab")
			(hide yes)
			(effects
				(font
					(size 1 1)
					(thickness 0.15)
				)
				(justify mirror)
			)
		)
		(property "Val" "1u"
			(at 0 0 0)
			(layer "B.Fab")
			(hide yes)
			(effects
				(font
					(size 1 1)
					(thickness 0.15)
				)
				(justify mirror)
			)
		)
		(property "Voltage" "16V"
			(at 0 0 0)
			(layer "B.Fab")
			(hide yes)
			(effects
				(font
					(size 1 1)
					(thickness 0.15)
				)
				(justify mirror)
			)
		)
		(sheetname "/LPDDR4/")
		(sheetfile "lpddr.kicad_sch")
		(attr smd)
		(fp_rect
			(start -0.925 0.47)
			(end 0.925 -0.47)
			(stroke
				(width 0.05)
				(type default)
			)
			(fill no)
			(layer "B.CrtYd")
		)
		(fp_line
			(start -0.494 -0.248)
			(end -0.494 0.25)
			(stroke
				(width 0.15)
				(type solid)
			)
			(layer "B.Fab")
		)
		(fp_line
			(start -0.494 0.25)
			(end 0.504 0.25)
			(stroke
				(width 0.15)
				(type solid)
			)
			(layer "B.Fab")
		)
		(fp_line
			(start 0.504 -0.248)
			(end -0.494 -0.248)
			(stroke
				(width 0.15)
				(type solid)
			)
			(layer "B.Fab")
		)
		(fp_line
			(start 0.504 0.25)
			(end 0.504 -0.248)
			(stroke
				(width 0.15)
				(type solid)
			)
			(layer "B.Fab")
		)
		(fp_text user "${REFERENCE}"
			(at -0.939 -4.599 180)
			(layer "B.Fab")
			(effects
				(font
					(size 0.7 0.7)
					(thickness 0.15)
				)
				(justify left bottom mirror)
			)
		)
		(fp_text user "Author: Antmicro"
			(at -0.939 -3.399 180)
			(layer "B.Fab")
			(effects
				(font
					(size 0.7 0.7)
					(thickness 0.15)
				)
				(justify left bottom mirror)
			)
		)
		(fp_text user "License: Apache-2.0"
			(at -0.939 -5.799 180)
			(layer "B.Fab")
			(effects
				(font
					(size 0.7 0.7)
					(thickness 0.15)
				)
				(justify left bottom mirror)
			)
		)
		(pad "1" smd roundrect
			(at -0.48 0)
			(size 0.59 0.64)
			(layers "B.Cu" "B.Mask" "B.Paste")
			(roundrect_rratio 0.25)
			(net 417 "GND")
			(pintype "passive")
		)
		(pad "2" smd roundrect
			(at 0.48 0)
			(size 0.59 0.64)
			(layers "B.Cu" "B.Mask" "B.Paste")
			(roundrect_rratio 0.25)
			(net 2 "+1V1")
			(pintype "passive")
		)
	)
)
